# S9S_MB_2U (Grand Teton) — schematic netlist excerpt (pin names and nets, part order shuffled) for the footprints in the layout excerpt that follows; sources: Cadence DE-HDL packaged netlist, KiCad conversion of 03242023_DA0F0TMBIJ0_F0T_Motherboard_J_brd_V01_OCP.brd

J17  SCONN288_ADR50017P130CC  SCONN288_ADR50017-P130CC IO  pkg DDR288S_1-1VXB  page 98
  VIN_BULK0  = P12V_S3_AUX_CPU1_NVDIMM
  RFU0  = TP_CHA_CPU1_DIMM1_FRU_0
  VIN_MGMT  = P3V3_AUX
  HSCL  = I3C_SPD_DDRABCD_CPU1_LVC1_SCL_R
  HSDA  = I3C_SPD_DDRABCD_CPU1_LVC1_SDA
  VSS0  = GND
  DQ0_A  = M_A_CPU1_SA_DQ<0>
  VSS1  = GND
  DQ1_A  = M_A_CPU1_SA_DQ<1>
  VSS2  = GND
  DQS0_A_T  = M_A_CPU1_SA_DQS_DP<0>
  DQS0_A_C  = M_A_CPU1_SA_DQS_DN<0>
  VSS3  = GND
  DQ4_A  = M_A_CPU1_SA_DQ<4>
  VSS4  = GND
  DQ5_A  = M_A_CPU1_SA_DQ<5>
  VSS5  = GND
  DQ8_A  = M_A_CPU1_SA_DQ<8>
  VSS6  = GND
  DQ9_A  = M_A_CPU1_SA_DQ<9>
  VSS7  = GND
  DQS1_A_T  = M_A_CPU1_SA_DQS_DP<1>
  DQS1_A_C  = M_A_CPU1_SA_DQS_DN<1>
  VSS8  = GND
  DQ12_A  = M_A_CPU1_SA_DQ<12>
  VSS9  = GND
  DQ13_A  = M_A_CPU1_SA_DQ<13>
  VSS10  = GND
  DQ16_A  = M_A_CPU1_SA_DQ<16>
  VSS11  = GND
  DQ17_A  = M_A_CPU1_SA_DQ<17>
  VSS12  = GND
  DQS2_A_T  = M_A_CPU1_SA_DQS_DP<2>
  DQS2_A_C  = M_A_CPU1_SA_DQS_DN<2>
  VSS13  = GND
  DQ20_A  = M_A_CPU1_SA_DQ<20>
  VSS14  = GND
  DQ21_A  = M_A_CPU1_SA_DQ<21>
  VSS15  = GND
  DQ24_A  = M_A_CPU1_SA_DQ<24>
  VSS16  = GND
  DQ25_A  = M_A_CPU1_SA_DQ<25>
  VSS17  = GND
  DQS3_A_T  = M_A_CPU1_SA_DQS_DP<3>
  DQS3_A_C  = M_A_CPU1_SA_DQS_DN<3>
  VSS18  = GND
  DQ28_A  = M_A_CPU1_SA_DQ<28>
  VSS19  = GND
  DQ29_A  = M_A_CPU1_SA_DQ<29>
  VSS20  = GND
  CB0_A  = M_A_CPU1_SA_CB<0>
  VSS21  = GND
  CB1_A  = M_A_CPU1_SA_CB<1>
  VSS22  = GND
  DQS4_A_T  = M_A_CPU1_SA_DQS_DP<4>
  DQS4_A_C  = M_A_CPU1_SA_DQS_DN<4>
  VSS23  = GND
  CB4_A  = M_A_CPU1_SA_CB<4>
  VSS24  = GND
  CB5_A  = M_A_CPU1_SA_CB<5>
  VSS25  = GND
  ALERT_N  = M_A_CPU1_ALERT_N
  VSS26  = GND
  CS0_A_N  = M_A_CPU1_SA_CS_N<0>
  VSS27  = GND
  CA0_A  = M_A_CPU1_SA_CA<0>
  VSS28  = GND
  CA2_A  = M_A_CPU1_SA_CA<2>
  VSS29  = GND
  CA4_A  = M_A_CPU1_SA_CA<4>
  VSS30  = GND
  CA6_A  = M_A_CPU1_SA_CA<6>
  VSS31  = GND
  PAR_A  = M_A_CPU1_SA_PAR
  VSS32  = GND
  CA0_B  = M_A_CPU1_SB_CA<0>
  VSS33  = GND
  CA2_B  = M_A_CPU1_SB_CA<2>
  VSS34  = GND
  CA4_B  = M_A_CPU1_SB_CA<4>
  VSS35  = GND
  CA6_B  = M_A_CPU1_SB_CA<6>
  VSS36  = GND
  CS0_B_N  = M_A_CPU1_SB_CS_N<0>
  VSS37  = GND
  \lbd||rsp_a_n\  = M_A_CPU1_SA_RSP<0>
  \lbs||rsp_b_n\  = M_A_CPU1_SB_RSP<0>
  VSS38  = GND
  CB4_B  = M_A_CPU1_SB_CB<4>
  VSS39  = GND
  CB5_B  = M_A_CPU1_SB_CB<5>
  VSS40  = GND
  \dqs9_b_t||tdqs9_b_t||dbi4_b_n\  = M_A_CPU1_SB_DQS_DP<9>
  \dqs9_b_c||tdqs9_b_c\  = M_A_CPU1_SB_DQS_DN<9>
  VSS41  = GND
  CB0_B  = M_A_CPU1_SB_CB<0>
  VSS42  = GND
  CB1_B  = M_A_CPU1_SB_CB<1>
  VSS43  = GND
  DQ0_B  = M_A_CPU1_SB_DQ<0>
  VSS44  = GND
  DQ1_B  = M_A_CPU1_SB_DQ<1>
  VSS45  = GND
  DQS0_B_T  = M_A_CPU1_SB_DQS_DP<0>
  DQS0_B_C  = M_A_CPU1_SB_DQS_DN<0>
  VSS46  = GND
  DQ4_B  = M_A_CPU1_SB_DQ<4>
  VSS47  = GND
  DQ5_B  = M_A_CPU1_SB_DQ<5>
  VSS48  = GND
  DQ8_B  = M_A_CPU1_SB_DQ<8>
  VSS49  = GND
  DQ9_B  = M_A_CPU1_SB_DQ<9>
  VSS50  = GND
  DQS1_B_T  = M_A_CPU1_SB_DQS_DP<1>
  DQS1_B_C  = M_A_CPU1_SB_DQS_DN<1>
  VSS51  = GND
  DQ12_B  = M_A_CPU1_SB_DQ<12>
  VSS52  = GND
  DQ13_B  = M_A_CPU1_SB_DQ<13>
  VSS53  = GND
  DQ16_B  = M_A_CPU1_SB_DQ<16>
  VSS54  = GND
  DQ17_B  = M_A_CPU1_SB_DQ<17>
  VSS55  = GND
  DQS2_B_T  = M_A_CPU1_SB_DQS_DP<2>
  DQS2_B_C  = M_A_CPU1_SB_DQS_DN<2>
  VSS56  = GND
  DQ20_B  = M_A_CPU1_SB_DQ<20>
  VSS57  = GND
  DQ21_B  = M_A_CPU1_SB_DQ<21>
  VSS58  = GND
  DQ24_B  = M_A_CPU1_SB_DQ<24>
  VSS59  = GND
  DQ25_B  = M_A_CPU1_SB_DQ<25>
  VSS60  = GND
  DQS3_B_T  = M_A_CPU1_SB_DQS_DP<3>
  DQS3_B_C  = M_A_CPU1_SB_DQS_DN<3>
  VSS61  = GND
  DQ28_B  = M_A_CPU1_SB_DQ<28>
  VSS62  = GND
  DQ29_B  = M_A_CPU1_SB_DQ<29>
  VSS63  = GND
  RFU1  = TP_CHA_CPU1_DIMM1_FRU_1
  VIN_BULK1  = P12V_S3_AUX_CPU1_NVDIMM
  VIN_BULK2  = P12V_S3_AUX_CPU1_NVDIMM
  \pwr_good||fail_n\  = PWRGD_CHA_CPU1_DIMM1
  HSA  = PD_CHA_CPU1_DIMM1_SAA
  RFU2  = TP_CHA_CPU1_DIMM1_FRU_2
  RFU3  = TP_CHA_CPU1_DIMM1_FRU_3
  VSS64  = GND
  DQ2_A  = M_A_CPU1_SA_DQ<2>
  VSS65  = GND
  DQ3_A  = M_A_CPU1_SA_DQ<3>
  VSS66  = GND
  \dqs5_a_c||tdqs5_a_c||dqs5_a_t||tdqs5_a_t\  = M_A_CPU1_SA_DQS_DN<5>
  \dqs5_a_t||tdqs5_a_t\  = M_A_CPU1_SA_DQS_DP<5>
  VSS67  = GND
  DQ6_A  = M_A_CPU1_SA_DQ<6>
  VSS68  = GND
  DQ7_A  = M_A_CPU1_SA_DQ<7>
  VSS69  = GND
  DQ10_A  = M_A_CPU1_SA_DQ<10>
  VSS70  = GND
  DQ11_A  = M_A_CPU1_SA_DQ<11>
  VSS71  = GND
  \dqs6_a_c||tdqs6_a_c||dqs6_a_t||tdqs6_a_t\  = M_A_CPU1_SA_DQS_DN<6>
  \dqs6_a_t||tdqs6_a_t\  = M_A_CPU1_SA_DQS_DP<6>
  VSS72  = GND
  DQ14_A  = M_A_CPU1_SA_DQ<14>
  VSS73  = GND
  DQ15_A  = M_A_CPU1_SA_DQ<15>
  VSS74  = GND
  DQ18_A  = M_A_CPU1_SA_DQ<18>
  VSS75  = GND
  DQ19_A  = M_A_CPU1_SA_DQ<19>
  VSS76  = GND
  \dqs7_a_c||tdqs7_a_c\  = M_A_CPU1_SA_DQS_DN<7>
  \dqs7_a_t||tdqs7_a_t\  = M_A_CPU1_SA_DQS_DP<7>
  VSS77  = GND
  DQ22_A  = M_A_CPU1_SA_DQ<22>
  VSS78  = GND
  DQ23_A  = M_A_CPU1_SA_DQ<23>
  VSS79  = GND
  DQ26_A  = M_A_CPU1_SA_DQ<26>
  VSS80  = GND
  DQ27_A  = M_A_CPU1_SA_DQ<27>
  VSS81  = GND
  \dqs8_a_c||tdqs8_a_c\  = M_A_CPU1_SA_DQS_DN<8>
  \dqs8_a_t||tdqs8_a_t\  = M_A_CPU1_SA_DQS_DP<8>
  VSS82  = GND
  DQ30_A  = M_A_CPU1_SA_DQ<30>
  VSS83  = GND
  DQ31_A  = M_A_CPU1_SA_DQ<31>
  VSS84  = GND
  CB2_A  = M_A_CPU1_SA_CB<2>
  VSS85  = GND
  CB3_A  = M_A_CPU1_SA_CB<3>
  VSS86  = GND
  \dqs9_a_c||tdqs9_a_c\  = M_A_CPU1_SA_DQS_DN<9>
  \dqs9_a_t||tdqs9_a_t\  = M_A_CPU1_SA_DQS_DP<9>
  VSS87  = GND
  CB6_A  = M_A_CPU1_SA_CB<6>
  VSS88  = GND
  CB7_A  = M_A_CPU1_SA_CB<7>
  VSS89  = GND
  RESET_N  = RST_M_AB_CPU1_FPGA_N
  VSS90  = GND
  CS1_A_N  = M_A_CPU1_SA_CS_N<1>
  VSS91  = GND
  CA1_A  = M_A_CPU1_SA_CA<1>
  VSS92  = GND
  CA3_A  = M_A_CPU1_SA_CA<3>
  VSS93  = GND
  CA5_A  = M_A_CPU1_SA_CA<5>
  VSS94  = GND
  CK_T  = M_A_CPU1_CLK_DP<0>
  CK_C  = M_A_CPU1_CLK_DN<0>
  VSS95  = GND
  RFU4  = TP_CHA_CPU1_DIMM1_FRU_4
  CA1_B  = M_A_CPU1_SB_CA<1>
  VSS96  = GND
  CA3_B  = M_A_CPU1_SB_CA<3>
  VSS97  = GND
  CA5_B  = M_A_CPU1_SB_CA<5>
  VSS98  = GND
  PAR_B  = M_A_CPU1_SB_PAR
  VSS99  = GND
  CS1_B_N  = M_A_CPU1_SB_CS_N<1>
  VSS100  = GND
  RFU5  = TP_CHA_CPU1_DIMM1_FRU_5
  RFU6  = TP_CHA_CPU1_DIMM1_FRU_6
  VSS101  = GND
  CB6_B  = M_A_CPU1_SB_CB<6>
  VSS102  = GND
  CB7_B  = M_A_CPU1_SB_CB<7>
  VSS103  = GND
  DQS4_B_C  = M_A_CPU1_SB_DQS_DN<4>
  DQS4_B_T  = M_A_CPU1_SB_DQS_DP<4>
  VSS104  = GND
  CB2_B  = M_A_CPU1_SB_CB<2>
  VSS105  = GND
  CB3_B  = M_A_CPU1_SB_CB<3>
  VSS106  = GND
  DQ2_B  = M_A_CPU1_SB_DQ<2>
  VSS107  = GND
  DQ3_B  = M_A_CPU1_SB_DQ<3>
  VSS108  = GND
  \dqs5_b_c||tdqs5_b_c\  = M_A_CPU1_SB_DQS_DN<5>
  \dqs5_b_t||tdqs5_b_t\  = M_A_CPU1_SB_DQS_DP<5>
  VSS109  = GND
  DQ6_B  = M_A_CPU1_SB_DQ<6>
  VSS110  = GND
  DQ7_B  = M_A_CPU1_SB_DQ<7>
  VSS111  = GND
  DQ10_B  = M_A_CPU1_SB_DQ<10>
  VSS112  = GND
  DQ11_B  = M_A_CPU1_SB_DQ<11>
  VSS113  = GND
  \dqs6_b_c||tdqs6_b_c\  = M_A_CPU1_SB_DQS_DN<6>
  \dqs6_b_t||tdqs6_b_t\  = M_A_CPU1_SB_DQS_DP<6>
  VSS114  = GND
  DQ14_B  = M_A_CPU1_SB_DQ<14>
  VSS115  = GND
  DQ15_B  = M_A_CPU1_SB_DQ<15>
  VSS116  = GND
  DQ18_B  = M_A_CPU1_SB_DQ<18>
  VSS117  = GND
  DQ19_B  = M_A_CPU1_SB_DQ<19>
  VSS118  = GND
  \dqs7_b_c||tdqs7_b_c\  = M_A_CPU1_SB_DQS_DN<7>
  \dqs7_b_t||tdqs7_b_t\  = M_A_CPU1_SB_DQS_DP<7>
  VSS119  = GND
  DQ22_B  = M_A_CPU1_SB_DQ<22>
  VSS120  = GND
  DQ23_B  = M_A_CPU1_SB_DQ<23>
  VSS121  = GND
  DQ26_B  = M_A_CPU1_SB_DQ<26>
  VSS122  = GND
  DQ27_B  = M_A_CPU1_SB_DQ<27>
  VSS123  = GND
  \dqs8_b_c||tdqs8_b_c\  = M_A_CPU1_SB_DQS_DN<8>
  \dqs8_b_t||tdqs8_b_t\  = M_A_CPU1_SB_DQS_DP<8>
  VSS124  = GND
  DQ30_B  = M_A_CPU1_SB_DQ<30>
  VSS125  = GND
  DQ31_B  = M_A_CPU1_SB_DQ<31>
  VSS126  = GND
  G1  = GND
  G2  = GND
  G3  = GND

(kicad_pcb
	(version 20260206)
	(generator "pcbnew")
	(generator_version "10.0")
	(general
		(thickness 1.6)
		(legacy_teardrops no)
	)
	(paper "A4")
	(title_block
		(title "03242023_DA0F0TMBIJ0_F0T_Motherboard_J_brd_V01_OCP.brd")
		(comment 1 "Grand Teton / footprint 1335 of 6105 (J17), pads 92-137 of 291")
	)
	(layers
		(0 "F.Cu" signal "TOP")
		(4 "In1.Cu" signal "GND")
		(6 "In2.Cu" signal "IN1")
		(8 "In3.Cu" signal "GND1")
		(10 "In4.Cu" signal "IN2")
		(12 "In5.Cu" signal "GND2")
		(14 "In6.Cu" signal "IN3")
		(16 "In7.Cu" signal "GND3")
		(18 "In8.Cu" signal "VCC")
		(20 "In9.Cu" signal "VCC1")
		(22 "In10.Cu" signal "GND4")
		(24 "In11.Cu" signal "IN4")
		(26 "In12.Cu" signal "GND5")
		(28 "In13.Cu" signal "IN5")
		(30 "In14.Cu" signal "GND6")
		(32 "In15.Cu" signal "IN6")
		(34 "In16.Cu" signal "GND7")
		(2 "B.Cu" signal "BOTTOM")
		(9 "F.Adhes" user "F.Adhesive")
		(11 "B.Adhes" user "B.Adhesive")
		(13 "F.Paste" user "Package Geometry/Pastemask Top")
		(15 "B.Paste" user "Package Geometry/Pastemask Bottom")
		(5 "F.SilkS" user "Ref Des/Silkscreen Top")
		(7 "B.SilkS" user "Ref Des/Silkscreen Bottom")
		(1 "F.Mask" user "Board Geometry/Soldermask Top")
		(3 "B.Mask" user "Board Geometry/Soldermask Bottom")
		(17 "Dwgs.User" user "User.Drawings")
		(19 "Cmts.User" user "User.Comments")
		(21 "Eco1.User" user "User.Eco1")
		(23 "Eco2.User" user "User.Eco2")
		(25 "Edge.Cuts" user "Board Geometry/Outline")
		(27 "Margin" user)
		(31 "F.CrtYd" user "Package Geometry/Place Bound Top")
		(29 "B.CrtYd" user "Package Geometry/Place Bound Bottom")
		(35 "F.Fab" user "Ref Des/Assembly Top")
		(33 "B.Fab" user "Ref Des/Assembly Bottom")
	)
	(footprint ""
		(layer "F.Cu")
		(at 55.45328 -258.091686)
		(property "Reference" "J17"
			(at -0.178562 -81.717134 0)
			(unlocked yes)
			(layer "F.SilkS")
			(effects
				(font
					(size 0.7874 0.5842)
					(thickness 0.1524)
				)
				(justify left)
			)
		)
		(property "Value" ""
			(at 0 0 0)
			(layer "F.Fab")
			(effects
				(font
					(size 1.27 1.27)
				)
			)
		)
		(duplicate_pad_numbers_are_jumpers no)
		(pad "92" smd rect
			(at -2.050034 19.12493 270)
			(size 0.519938 1.4986)
			(layers "F.Cu" "F.Mask" "F.Paste")
			(net "GND")
		)
		(pad "93" smd rect
			(at -2.050034 19.975068 270)
			(size 0.519938 1.4986)
			(layers "F.Cu" "F.Mask" "F.Paste")
			(net "M_A_CPU1_SB_DQS_DP<9>")
		)
		(pad "94" smd rect
			(at -2.050034 20.824952 270)
			(size 0.519938 1.4986)
			(layers "F.Cu" "F.Mask" "F.Paste")
			(net "M_A_CPU1_SB_DQS_DN<9>")
		)
		(pad "95" smd rect
			(at -2.050034 21.67509 270)
			(size 0.519938 1.4986)
			(layers "F.Cu" "F.Mask" "F.Paste")
			(net "GND")
		)
		(pad "96" smd rect
			(at -2.050034 22.524974 270)
			(size 0.519938 1.4986)
			(layers "F.Cu" "F.Mask" "F.Paste")
			(net "M_A_CPU1_SB_CB<0>")
		)
		(pad "97" smd rect
			(at -2.050034 23.375112 270)
			(size 0.519938 1.4986)
			(layers "F.Cu" "F.Mask" "F.Paste")
			(net "GND")
		)
		(pad "98" smd rect
			(at -2.050034 24.224996 270)
			(size 0.519938 1.4986)
			(layers "F.Cu" "F.Mask" "F.Paste")
			(net "M_A_CPU1_SB_CB<1>")
		)
		(pad "99" smd rect
			(at -2.050034 25.07488 270)
			(size 0.519938 1.4986)
			(layers "F.Cu" "F.Mask" "F.Paste")
			(net "GND")
		)
		(pad "100" smd rect
			(at -2.050034 25.925018 270)
			(size 0.519938 1.4986)
			(layers "F.Cu" "F.Mask" "F.Paste")
			(net "M_A_CPU1_SB_DQ<0>")
		)
		(pad "101" smd rect
			(at -2.050034 26.774902 270)
			(size 0.519938 1.4986)
			(layers "F.Cu" "F.Mask" "F.Paste")
			(net "GND")
		)
		(pad "102" smd rect
			(at -2.050034 27.62504 270)
			(size 0.519938 1.4986)
			(layers "F.Cu" "F.Mask" "F.Paste")
			(net "M_A_CPU1_SB_DQ<1>")
		)
		(pad "103" smd rect
			(at -2.050034 28.474924 270)
			(size 0.519938 1.4986)
			(layers "F.Cu" "F.Mask" "F.Paste")
			(net "GND")
		)
		(pad "104" smd rect
			(at -2.050034 29.325062 270)
			(size 0.519938 1.4986)
			(layers "F.Cu" "F.Mask" "F.Paste")
			(net "M_A_CPU1_SB_DQS_DP<0>")
		)
		(pad "105" smd rect
			(at -2.050034 30.174946 270)
			(size 0.519938 1.4986)
			(layers "F.Cu" "F.Mask" "F.Paste")
			(net "M_A_CPU1_SB_DQS_DN<0>")
		)
		(pad "106" smd rect
			(at -2.050034 31.025084 270)
			(size 0.519938 1.4986)
			(layers "F.Cu" "F.Mask" "F.Paste")
			(net "GND")
		)
		(pad "107" smd rect
			(at -2.050034 31.874968 270)
			(size 0.519938 1.4986)
			(layers "F.Cu" "F.Mask" "F.Paste")
			(net "M_A_CPU1_SB_DQ<4>")
		)
		(pad "108" smd rect
			(at -2.050034 32.725106 270)
			(size 0.519938 1.4986)
			(layers "F.Cu" "F.Mask" "F.Paste")
			(net "GND")
		)
		(pad "109" smd rect
			(at -2.050034 33.57499 270)
			(size 0.519938 1.4986)
			(layers "F.Cu" "F.Mask" "F.Paste")
			(net "M_A_CPU1_SB_DQ<5>")
		)
		(pad "110" smd rect
			(at -2.050034 34.425128 270)
			(size 0.519938 1.4986)
			(layers "F.Cu" "F.Mask" "F.Paste")
			(net "GND")
		)
		(pad "111" smd rect
			(at -2.050034 35.275012 270)
			(size 0.519938 1.4986)
			(layers "F.Cu" "F.Mask" "F.Paste")
			(net "M_A_CPU1_SB_DQ<8>")
		)
		(pad "112" smd rect
			(at -2.050034 36.124896 270)
			(size 0.519938 1.4986)
			(layers "F.Cu" "F.Mask" "F.Paste")
			(net "GND")
		)
		(pad "113" smd rect
			(at -2.050034 36.975034 270)
			(size 0.519938 1.4986)
			(layers "F.Cu" "F.Mask" "F.Paste")
			(net "M_A_CPU1_SB_DQ<9>")
		)
		(pad "114" smd rect
			(at -2.050034 37.824918 270)
			(size 0.519938 1.4986)
			(layers "F.Cu" "F.Mask" "F.Paste")
			(net "GND")
		)
		(pad "115" smd rect
			(at -2.050034 38.675056 270)
			(size 0.519938 1.4986)
			(layers "F.Cu" "F.Mask" "F.Paste")
			(net "M_A_CPU1_SB_DQS_DP<1>")
		)
		(pad "116" smd rect
			(at -2.050034 39.52494 270)
			(size 0.519938 1.4986)
			(layers "F.Cu" "F.Mask" "F.Paste")
			(net "M_A_CPU1_SB_DQS_DN<1>")
		)
		(pad "117" smd rect
			(at -2.050034 40.375078 270)
			(size 0.519938 1.4986)
			(layers "F.Cu" "F.Mask" "F.Paste")
			(net "GND")
		)
		(pad "118" smd rect
			(at -2.050034 41.224962 270)
			(size 0.519938 1.4986)
			(layers "F.Cu" "F.Mask" "F.Paste")
			(net "M_A_CPU1_SB_DQ<12>")
		)
		(pad "119" smd rect
			(at -2.050034 42.0751 270)
			(size 0.519938 1.4986)
			(layers "F.Cu" "F.Mask" "F.Paste")
			(net "GND")
		)
		(pad "120" smd rect
			(at -2.050034 42.924984 270)
			(size 0.519938 1.4986)
			(layers "F.Cu" "F.Mask" "F.Paste")
			(net "M_A_CPU1_SB_DQ<13>")
		)
		(pad "121" smd rect
			(at -2.050034 43.775122 270)
			(size 0.519938 1.4986)
			(layers "F.Cu" "F.Mask" "F.Paste")
			(net "GND")
		)
		(pad "122" smd rect
			(at -2.050034 44.625006 270)
			(size 0.519938 1.4986)
			(layers "F.Cu" "F.Mask" "F.Paste")
			(net "M_A_CPU1_SB_DQ<16>")
		)
		(pad "123" smd rect
			(at -2.050034 45.47489 270)
			(size 0.519938 1.4986)
			(layers "F.Cu" "F.Mask" "F.Paste")
			(net "GND")
		)
		(pad "124" smd rect
			(at -2.050034 46.325028 270)
			(size 0.519938 1.4986)
			(layers "F.Cu" "F.Mask" "F.Paste")
			(net "M_A_CPU1_SB_DQ<17>")
		)
		(pad "125" smd rect
			(at -2.050034 47.174912 270)
			(size 0.519938 1.4986)
			(layers "F.Cu" "F.Mask" "F.Paste")
			(net "GND")
		)
		(pad "126" smd rect
			(at -2.050034 48.02505 270)
			(size 0.519938 1.4986)
			(layers "F.Cu" "F.Mask" "F.Paste")
			(net "M_A_CPU1_SB_DQS_DP<2>")
		)
		(pad "127" smd rect
			(at -2.050034 48.874934 270)
			(size 0.519938 1.4986)
			(layers "F.Cu" "F.Mask" "F.Paste")
			(net "M_A_CPU1_SB_DQS_DN<2>")
		)
		(pad "128" smd rect
			(at -2.050034 49.725072 270)
			(size 0.519938 1.4986)
			(layers "F.Cu" "F.Mask" "F.Paste")
			(net "GND")
		)
		(pad "129" smd rect
			(at -2.050034 50.574956 270)
			(size 0.519938 1.4986)
			(layers "F.Cu" "F.Mask" "F.Paste")
			(net "M_A_CPU1_SB_DQ<20>")
		)
		(pad "130" smd rect
			(at -2.050034 51.425094 270)
			(size 0.519938 1.4986)
			(layers "F.Cu" "F.Mask" "F.Paste")
			(net "GND")
		)
		(pad "131" smd rect
			(at -2.050034 52.274978 270)
			(size 0.519938 1.4986)
			(layers "F.Cu" "F.Mask" "F.Paste")
			(net "M_A_CPU1_SB_DQ<21>")
		)
		(pad "132" smd rect
			(at -2.050034 53.125116 270)
			(size 0.519938 1.4986)
			(layers "F.Cu" "F.Mask" "F.Paste")
			(net "GND")
		)
		(pad "133" smd rect
			(at -2.050034 53.975 270)
			(size 0.519938 1.4986)
			(layers "F.Cu" "F.Mask" "F.Paste")
			(net "M_A_CPU1_SB_DQ<24>")
		)
		(pad "134" smd rect
			(at -2.050034 54.824884 270)
			(size 0.519938 1.4986)
			(layers "F.Cu" "F.Mask" "F.Paste")
			(net "GND")
		)
		(pad "135" smd rect
			(at -2.050034 55.675022 270)
			(size 0.519938 1.4986)
			(layers "F.Cu" "F.Mask" "F.Paste")
			(net "M_A_CPU1_SB_DQ<25>")
		)
		(pad "136" smd rect
			(at -2.050034 56.524906 270)
			(size 0.519938 1.4986)
			(layers "F.Cu" "F.Mask" "F.Paste")
			(net "GND")
		)
		(pad "137" smd rect
			(at -2.050034 57.375044 270)
			(size 0.519938 1.4986)
			(layers "F.Cu" "F.Mask" "F.Paste")
			(net "M_A_CPU1_SB_DQS_DP<3>")
		)
	)
)
